# T6G (Grand Teton) — schematic netlist excerpt (pin names and nets, part order shuffled) for the footprints in the layout excerpt that follows; sources: Cadence DE-HDL packaged netlist, KiCad conversion of 04192023_DAF0TMB3IC0_F0TG_MB_C_brd_V02_OCP.brd

R478  Q_RES  33 5% CHIP  pkg 0402LF  page 172 : A = CPU0_XTRIG_L5 ; B = HDT_CPU0_XTRIG_L5
R6103  Q_RES  0 5% CHIP  pkg 0402LF  page 173 : A = JTAG_CPUX_TDI_R1 ; B = JTAG_CPUX_TDI
H21  HOLE  EMPTY  pkg TH  page 230 : \1\ = GND
C813  Q_CAP_DIFFBUS  DIFF BUS_0.22UF 6.3V 20% X6S  pkg C0201  page 65 : \1\ = P5E_CPU1_P0_TX_C_DP<12> ; \2\ = P5E_CPU1_P0_TX_DP<12>

(kicad_pcb
	(version 20260206)
	(generator "pcbnew")
	(generator_version "10.0")
	(general
		(thickness 1.6)
		(legacy_teardrops no)
	)
	(paper "A4")
	(title_block
		(title "04192023_DAF0TMB3IC0_F0TG_MB_C_brd_V02_OCP.brd")
		(comment 1 "Grand Teton / footprints 3222-3225 of 8354")
	)
	(layers
		(0 "F.Cu" signal "TOP")
		(4 "In1.Cu" signal "GND")
		(6 "In2.Cu" signal "IN1")
		(8 "In3.Cu" signal "GND1")
		(10 "In4.Cu" signal "IN2")
		(12 "In5.Cu" signal "GND2")
		(14 "In6.Cu" signal "IN3")
		(16 "In7.Cu" signal "GND3")
		(18 "In8.Cu" signal "VCC")
		(20 "In9.Cu" signal "VCC1")
		(22 "In10.Cu" signal "GND4")
		(24 "In11.Cu" signal "IN4")
		(26 "In12.Cu" signal "GND5")
		(28 "In13.Cu" signal "IN5")
		(30 "In14.Cu" signal "GND6")
		(32 "In15.Cu" signal "IN6")
		(34 "In16.Cu" signal "GND7")
		(2 "B.Cu" signal "BOTTOM")
		(9 "F.Adhes" user "F.Adhesive")
		(11 "B.Adhes" user "B.Adhesive")
		(13 "F.Paste" user "Package Geometry/Pastemask Top")
		(15 "B.Paste" user "Package Geometry/Pastemask Bottom")
		(5 "F.SilkS" user "Ref Des/Silkscreen Top")
		(7 "B.SilkS" user "Ref Des/Silkscreen Bottom")
		(1 "F.Mask" user "Board Geometry/Soldermask Top")
		(3 "B.Mask" user "Board Geometry/Soldermask Bottom")
		(17 "Dwgs.User" user "User.Drawings")
		(19 "Cmts.User" user "User.Comments")
		(21 "Eco1.User" user "User.Eco1")
		(23 "Eco2.User" user "User.Eco2")
		(25 "Edge.Cuts" user "Board Geometry/Outline")
		(27 "Margin" user)
		(31 "F.CrtYd" user "Package Geometry/Place Bound Top")
		(29 "B.CrtYd" user "Package Geometry/Place Bound Bottom")
		(35 "F.Fab" user "Ref Des/Assembly Top")
		(33 "B.Fab" user "Ref Des/Assembly Bottom")
	)
	(footprint ""
		(layer "F.Cu")
		(at 112.716056 -340.315042)
		(property "Reference" "H21"
			(at -3.900424 -4.48056 0)
			(unlocked yes)
			(layer "F.SilkS")
			(effects
				(font
					(size 0.7874 0.5842)
					(thickness 0.1524)
				)
				(justify left)
			)
		)
		(property "Value" ""
			(at 0 0 0)
			(layer "F.Fab")
			(effects
				(font
					(size 1.27 1.27)
				)
			)
		)
		(duplicate_pad_numbers_are_jumpers no)
		(pad "1" thru_hole circle
			(at 0 0)
			(size 6.1976 6.1976)
			(drill 3.7338)
			(layers "*.Cu" "*.Mask")
			(remove_unused_layers no)
			(net "GND")
			(clearance -0.9779)
			(padstack
				(mode front_inner_back)
				(layer "Inner"
					(shape circle)
					(size 5.5372 5.5372)
					(clearance -0.6477)
				)
				(layer "B.Cu"
					(shape circle)
					(size 6.1976 6.1976)
					(clearance -0.9779)
				)
			)
		)
	)
	(footprint ""
		(layer "F.Cu")
		(at 127.705104 -55.922164 180)
		(property "Reference" "R6103"
			(at 0 0 180)
			(layer "F.SilkS")
			(hide yes)
			(effects
				(font
					(size 1.27 1.27)
				)
			)
		)
		(property "Value" ""
			(at 0 0 180)
			(layer "F.Fab")
			(effects
				(font
					(size 1.27 1.27)
				)
			)
		)
		(duplicate_pad_numbers_are_jumpers no)
		(fp_line
			(start 0.7874 0.4064)
			(end -0.7874 0.4064)
			(stroke
				(width 0.1524)
				(type default)
			)
			(layer "F.SilkS")
		)
		(fp_line
			(start 0.7874 -0.4064)
			(end 0.7874 0.4064)
			(stroke
				(width 0.1524)
				(type default)
			)
			(layer "F.SilkS")
		)
		(fp_line
			(start -0.7874 0.4064)
			(end -0.7874 -0.4064)
			(stroke
				(width 0.1524)
				(type default)
			)
			(layer "F.SilkS")
		)
		(fp_line
			(start -0.7874 -0.4064)
			(end 0.7874 -0.4064)
			(stroke
				(width 0.1524)
				(type default)
			)
			(layer "F.SilkS")
		)
		(fp_line
			(start 0.67945 0.3048)
			(end 0.120396 0.3048)
			(stroke
				(width 0.1)
				(type default)
			)
			(layer "F.Fab")
		)
		(fp_line
			(start 0.67945 -0.3048)
			(end 0.67945 0.3048)
			(stroke
				(width 0.1)
				(type default)
			)
			(layer "F.Fab")
		)
		(fp_line
			(start 0.12065 -0.2794)
			(end 0.12065 -0.3048)
			(stroke
				(width 0.1)
				(type default)
			)
			(layer "F.Fab")
		)
		(fp_line
			(start 0.12065 -0.3048)
			(end 0.67945 -0.3048)
			(stroke
				(width 0.1)
				(type default)
			)
			(layer "F.Fab")
		)
		(fp_line
			(start 0.120396 0.3048)
			(end 0.120396 0.2794)
			(stroke
				(width 0.1)
				(type default)
			)
			(layer "F.Fab")
		)
		(fp_line
			(start 0.120396 0.2794)
			(end -0.12065 0.2794)
			(stroke
				(width 0.1)
				(type default)
			)
			(layer "F.Fab")
		)
		(fp_line
			(start -0.12065 0.3048)
			(end -0.67945 0.3048)
			(stroke
				(width 0.1)
				(type default)
			)
			(layer "F.Fab")
		)
		(fp_line
			(start -0.12065 0.2794)
			(end -0.12065 0.3048)
			(stroke
				(width 0.1)
				(type default)
			)
			(layer "F.Fab")
		)
		(fp_line
			(start -0.12065 -0.2794)
			(end 0.12065 -0.2794)
			(stroke
				(width 0.1)
				(type default)
			)
			(layer "F.Fab")
		)
		(fp_line
			(start -0.12065 -0.305054)
			(end -0.12065 -0.2794)
			(stroke
				(width 0.1)
				(type default)
			)
			(layer "F.Fab")
		)
		(fp_line
			(start -0.67945 0.3048)
			(end -0.67945 -0.305054)
			(stroke
				(width 0.1)
				(type default)
			)
			(layer "F.Fab")
		)
		(fp_line
			(start -0.67945 -0.305054)
			(end -0.12065 -0.305054)
			(stroke
				(width 0.1)
				(type default)
			)
			(layer "F.Fab")
		)
		(pad "1" smd circle
			(at -0.40005 0 180)
			(size 0 0)
			(layers "F.Cu" "F.Mask" "F.Paste")
			(net "JTAG_CPUX_TDI_R1")
		)
		(pad "2" smd circle
			(at 0.40005 0 180)
			(size 0 0)
			(layers "F.Cu" "F.Mask" "F.Paste")
			(net "JTAG_CPUX_TDI")
		)
	)
	(footprint ""
		(layer "F.Cu")
		(at 65.113154 -370.57203 -90)
		(property "Reference" "C813"
			(at 0 0 270)
			(layer "F.SilkS")
			(hide yes)
			(effects
				(font
					(size 1.27 1.27)
				)
			)
		)
		(property "Value" ""
			(at 0 0 270)
			(layer "F.Fab")
			(effects
				(font
					(size 1.27 1.27)
				)
			)
		)
		(duplicate_pad_numbers_are_jumpers no)
		(fp_line
			(start -0.299974 0.150114)
			(end -0.299974 -0.150114)
			(stroke
				(width 0.1)
				(type default)
			)
			(layer "F.Fab")
		)
		(fp_line
			(start 0.299974 0.150114)
			(end -0.299974 0.150114)
			(stroke
				(width 0.1)
				(type default)
			)
			(layer "F.Fab")
		)
		(fp_line
			(start -0.299974 -0.150114)
			(end 0.299974 -0.150114)
			(stroke
				(width 0.1)
				(type default)
			)
			(layer "F.Fab")
		)
		(fp_line
			(start 0.299974 -0.150114)
			(end 0.299974 0.150114)
			(stroke
				(width 0.1)
				(type default)
			)
			(layer "F.Fab")
		)
		(pad "1" smd rect
			(at -0.2667 0 270)
			(size 0.3048 0.381)
			(layers "F.Cu" "F.Mask" "F.Paste")
			(net "P5E_CPU1_P0_TX_C_DP<12>")
		)
		(pad "2" smd rect
			(at 0.2667 0 270)
			(size 0.3048 0.381)
			(layers "F.Cu" "F.Mask" "F.Paste")
			(net "P5E_CPU1_P0_TX_DP<12>")
		)
	)
	(footprint ""
		(layer "F.Cu")
		(at 403.682962 -62.0395 180)
		(property "Reference" "R478"
			(at 0 0 180)
			(layer "F.SilkS")
			(hide yes)
			(effects
				(font
					(size 1.27 1.27)
				)
			)
		)
		(property "Value" ""
			(at 0 0 180)
			(layer "F.Fab")
			(effects
				(font
					(size 1.27 1.27)
				)
			)
		)
		(duplicate_pad_numbers_are_jumpers no)
		(fp_line
			(start 0.7874 0.4064)
			(end -0.7874 0.4064)
			(stroke
				(width 0.1524)
				(type default)
			)
			(layer "F.SilkS")
		)
		(fp_line
			(start 0.7874 -0.4064)
			(end 0.7874 0.4064)
			(stroke
				(width 0.1524)
				(type default)
			)
			(layer "F.SilkS")
		)
		(fp_line
			(start -0.7874 0.4064)
			(end -0.7874 -0.4064)
			(stroke
				(width 0.1524)
				(type default)
			)
			(layer "F.SilkS")
		)
		(fp_line
			(start -0.7874 -0.4064)
			(end 0.7874 -0.4064)
			(stroke
				(width 0.1524)
				(type default)
			)
			(layer "F.SilkS")
		)
		(fp_line
			(start 0.67945 0.3048)
			(end 0.120396 0.3048)
			(stroke
				(width 0.1)
				(type default)
			)
			(layer "F.Fab")
		)
		(fp_line
			(start 0.67945 -0.3048)
			(end 0.67945 0.3048)
			(stroke
				(width 0.1)
				(type default)
			)
			(layer "F.Fab")
		)
		(fp_line
			(start 0.12065 -0.2794)
			(end 0.12065 -0.3048)
			(stroke
				(width 0.1)
				(type default)
			)
			(layer "F.Fab")
		)
		(fp_line
			(start 0.12065 -0.3048)
			(end 0.67945 -0.3048)
			(stroke
				(width 0.1)
				(type default)
			)
			(layer "F.Fab")
		)
		(fp_line
			(start 0.120396 0.3048)
			(end 0.120396 0.2794)
			(stroke
				(width 0.1)
				(type default)
			)
			(layer "F.Fab")
		)
		(fp_line
			(start 0.120396 0.2794)
			(end -0.12065 0.2794)
			(stroke
				(width 0.1)
				(type default)
			)
			(layer "F.Fab")
		)
		(fp_line
			(start -0.12065 0.3048)
			(end -0.67945 0.3048)
			(stroke
				(width 0.1)
				(type default)
			)
			(layer "F.Fab")
		)
		(fp_line
			(start -0.12065 0.2794)
			(end -0.12065 0.3048)
			(stroke
				(width 0.1)
				(type default)
			)
			(layer "F.Fab")
		)
		(fp_line
			(start -0.12065 -0.2794)
			(end 0.12065 -0.2794)
			(stroke
				(width 0.1)
				(type default)
			)
			(layer "F.Fab")
		)
		(fp_line
			(start -0.12065 -0.305054)
			(end -0.12065 -0.2794)
			(stroke
				(width 0.1)
				(type default)
			)
			(layer "F.Fab")
		)
		(fp_line
			(start -0.67945 0.3048)
			(end -0.67945 -0.305054)
			(stroke
				(width 0.1)
				(type default)
			)
			(layer "F.Fab")
		)
		(fp_line
			(start -0.67945 -0.305054)
			(end -0.12065 -0.305054)
			(stroke
				(width 0.1)
				(type default)
			)
			(layer "F.Fab")
		)
		(pad "1" smd circle
			(at -0.40005 0 180)
			(size 0 0)
			(layers "F.Cu" "F.Mask" "F.Paste")
			(net "CPU0_XTRIG_L5")
		)
		(pad "2" smd circle
			(at 0.40005 0 180)
			(size 0 0)
			(layers "F.Cu" "F.Mask" "F.Paste")
			(net "HDT_CPU0_XTRIG_L5")
		)
	)
)
